(kicad_pcb
	(version 20260206)
	(generator "pcbnew")
	(generator_version "10.0")
	(general
		(thickness 1.6)
		(legacy_teardrops no)
	)
	(paper "A4")
	(title_block
		(title "9052_F0T_PDB_Converter_Brick_F_V03_1208_1600_OCP.brd")
		(comment 1 "Grand Teton / footprints 29-34 of 578")
	)
	(layers
		(0 "F.Cu" signal "TOP")
		(4 "In1.Cu" signal "GND")
		(6 "In2.Cu" signal "IN1")
		(8 "In3.Cu" signal "GND1")
		(10 "In4.Cu" signal "VCC")
		(12 "In5.Cu" signal "VCC1")
		(14 "In6.Cu" signal "GND2")
		(16 "In7.Cu" signal "IN2")
		(18 "In8.Cu" signal "GND3")
		(2 "B.Cu" signal "BOTTOM")
		(9 "F.Adhes" user "F.Adhesive")
		(11 "B.Adhes" user "B.Adhesive")
		(13 "F.Paste" user "Package Geometry/Pastemask Top")
		(15 "B.Paste" user "Package Geometry/Pastemask Bottom")
		(5 "F.SilkS" user "Ref Des/Silkscreen Top")
		(7 "B.SilkS" user "Ref Des/Silkscreen Bottom")
		(1 "F.Mask" user "Board Geometry/Soldermask Top")
		(3 "B.Mask" user "Board Geometry/Soldermask Bottom")
		(17 "Dwgs.User" user "User.Drawings")
		(19 "Cmts.User" user "User.Comments")
		(21 "Eco1.User" user "User.Eco1")
		(23 "Eco2.User" user "User.Eco2")
		(25 "Edge.Cuts" user "Board Geometry/Outline")
		(27 "Margin" user)
		(31 "F.CrtYd" user "Package Geometry/Place Bound Top")
		(29 "B.CrtYd" user "Package Geometry/Place Bound Bottom")
		(35 "F.Fab" user "Ref Des/Assembly Top")
		(33 "B.Fab" user "Ref Des/Assembly Bottom")
	)
	(footprint ""
		(layer "F.Cu")
		(at 279.019 -42.799 180)
		(property "Reference" "PC562"
			(at 0 0 180)
			(layer "F.SilkS")
			(hide yes)
			(effects
				(font
					(size 1.27 1.27)
				)
			)
		)
		(property "Value" ""
			(at 0 0 180)
			(layer "F.Fab")
			(effects
				(font
					(size 1.27 1.27)
				)
			)
		)
		(duplicate_pad_numbers_are_jumpers no)
		(fp_line
			(start 1.2954 0.5842)
			(end -1.2954 0.5842)
			(stroke
				(width 0.1524)
				(type default)
			)
			(layer "F.SilkS")
		)
		(fp_line
			(start 1.2954 -0.5842)
			(end 1.2954 0.5842)
			(stroke
				(width 0.1524)
				(type default)
			)
			(layer "F.SilkS")
		)
		(fp_line
			(start -1.2954 0.5842)
			(end -1.2954 -0.5842)
			(stroke
				(width 0.1524)
				(type default)
			)
			(layer "F.SilkS")
		)
		(fp_line
			(start -1.2954 -0.5842)
			(end 1.2954 -0.5842)
			(stroke
				(width 0.1524)
				(type default)
			)
			(layer "F.SilkS")
		)
		(fp_line
			(start 1.1938 0.4064)
			(end 0.8636 0.4064)
			(stroke
				(width 0.1)
				(type default)
			)
			(layer "F.Fab")
		)
		(fp_line
			(start 1.1938 -0.4064)
			(end 1.1938 0.4064)
			(stroke
				(width 0.1)
				(type default)
			)
			(layer "F.Fab")
		)
		(fp_line
			(start 0.8636 0.4572)
			(end -0.8636 0.4572)
			(stroke
				(width 0.1)
				(type default)
			)
			(layer "F.Fab")
		)
		(fp_line
			(start 0.8636 0.4064)
			(end 0.8636 0.4572)
			(stroke
				(width 0.1)
				(type default)
			)
			(layer "F.Fab")
		)
		(fp_line
			(start 0.8636 -0.4064)
			(end 1.1938 -0.4064)
			(stroke
				(width 0.1)
				(type default)
			)
			(layer "F.Fab")
		)
		(fp_line
			(start 0.8636 -0.4572)
			(end 0.8636 -0.4064)
			(stroke
				(width 0.1)
				(type default)
			)
			(layer "F.Fab")
		)
		(fp_line
			(start -0.8636 0.4572)
			(end -0.8636 0.4064)
			(stroke
				(width 0.1)
				(type default)
			)
			(layer "F.Fab")
		)
		(fp_line
			(start -0.8636 0.4064)
			(end -1.1938 0.4064)
			(stroke
				(width 0.1)
				(type default)
			)
			(layer "F.Fab")
		)
		(fp_line
			(start -0.8636 -0.4064)
			(end -0.8636 -0.4572)
			(stroke
				(width 0.1)
				(type default)
			)
			(layer "F.Fab")
		)
		(fp_line
			(start -0.8636 -0.4572)
			(end 0.8636 -0.4572)
			(stroke
				(width 0.1)
				(type default)
			)
			(layer "F.Fab")
		)
		(fp_line
			(start -1.1938 0.4064)
			(end -1.1938 -0.4064)
			(stroke
				(width 0.1)
				(type default)
			)
			(layer "F.Fab")
		)
		(fp_line
			(start -1.1938 -0.4064)
			(end -0.8636 -0.4064)
			(stroke
				(width 0.1)
				(type default)
			)
			(layer "F.Fab")
		)
		(pad "1" smd rect
			(at -0.7366 0 90)
			(size 0.7112 0.8128)
			(layers "F.Cu" "F.Mask" "F.Paste")
			(net "P52V_HS1_VCAP")
		)
		(pad "2" smd rect
			(at 0.7366 0 90)
			(size 0.7112 0.8128)
			(layers "F.Cu" "F.Mask" "F.Paste")
			(net "GND_FIELD_SIGNAL")
		)
	)
	(footprint ""
		(layer "F.Cu")
		(at 149.098 -127.889)
		(property "Reference" "PC19"
			(at 0 0 0)
			(layer "F.SilkS")
			(hide yes)
			(effects
				(font
					(size 1.27 1.27)
				)
			)
		)
		(property "Value" ""
			(at 0 0 0)
			(layer "F.Fab")
			(effects
				(font
					(size 1.27 1.27)
				)
			)
		)
		(duplicate_pad_numbers_are_jumpers no)
		(fp_line
			(start -2.2098 -0.9398)
			(end 2.2098 -0.9398)
			(stroke
				(width 0.1524)
				(type default)
			)
			(layer "F.SilkS")
		)
		(fp_line
			(start -2.2098 0.9398)
			(end -2.2098 -0.9398)
			(stroke
				(width 0.1524)
				(type default)
			)
			(layer "F.SilkS")
		)
		(fp_line
			(start 2.2098 -0.9398)
			(end 2.2098 0.9398)
			(stroke
				(width 0.1524)
				(type default)
			)
			(layer "F.SilkS")
		)
		(fp_line
			(start 2.2098 0.9398)
			(end -2.2098 0.9398)
			(stroke
				(width 0.1524)
				(type default)
			)
			(layer "F.SilkS")
		)
		(fp_line
			(start -1.700022 -0.899922)
			(end 1.700022 -0.899922)
			(stroke
				(width 0.1)
				(type default)
			)
			(layer "F.Fab")
		)
		(fp_line
			(start -1.700022 0.899922)
			(end -1.700022 -0.899922)
			(stroke
				(width 0.1)
				(type default)
			)
			(layer "F.Fab")
		)
		(fp_line
			(start 1.700022 -0.899922)
			(end 1.700022 0.899922)
			(stroke
				(width 0.1)
				(type default)
			)
			(layer "F.Fab")
		)
		(fp_line
			(start 1.700022 0.899922)
			(end -1.700022 0.899922)
			(stroke
				(width 0.1)
				(type default)
			)
			(layer "F.Fab")
		)
		(pad "1" smd rect
			(at -1.4732 0 180)
			(size 1.1684 1.5748)
			(layers "F.Cu" "F.Mask" "F.Paste")
			(net "P52V_HS_FILTER")
		)
		(pad "2" smd rect
			(at 1.4732 0 180)
			(size 1.1684 1.5748)
			(layers "F.Cu" "F.Mask" "F.Paste")
			(net "GND")
		)
	)
	(footprint ""
		(layer "F.Cu")
		(at 21.02993 -122.48007 -90)
		(property "Reference" "J14"
			(at 6.17474 -8.43407 0)
			(unlocked yes)
			(layer "F.SilkS")
			(effects
				(font
					(size 0.7874 0.5842)
					(thickness 0.1524)
				)
				(justify left)
			)
		)
		(property "Value" ""
			(at 0 0 270)
			(layer "F.Fab")
			(effects
				(font
					(size 1.27 1.27)
				)
			)
		)
		(duplicate_pad_numbers_are_jumpers no)
		(fp_line
			(start -5.32511 21.299932)
			(end -5.32511 -10.500106)
			(stroke
				(width 0.1524)
				(type default)
			)
			(layer "F.SilkS")
		)
		(fp_line
			(start 5.32511 21.299932)
			(end -5.32511 21.299932)
			(stroke
				(width 0.1524)
				(type default)
			)
			(layer "F.SilkS")
		)
		(fp_line
			(start -5.32511 10.6299)
			(end 5.32511 10.6299)
			(stroke
				(width 0.1524)
				(type default)
			)
			(layer "F.SilkS")
		)
		(fp_line
			(start -5.32511 -10.500106)
			(end 5.32511 -10.500106)
			(stroke
				(width 0.1524)
				(type default)
			)
			(layer "F.SilkS")
		)
		(fp_line
			(start 5.32511 -10.500106)
			(end 5.32511 21.299932)
			(stroke
				(width 0.1524)
				(type default)
			)
			(layer "F.SilkS")
		)
		(fp_line
			(start -5.32511 21.299932)
			(end -5.32511 -10.500106)
			(stroke
				(width 0.1)
				(type default)
			)
			(layer "F.Fab")
		)
		(fp_line
			(start 5.32511 21.299932)
			(end -5.32511 21.299932)
			(stroke
				(width 0.1)
				(type default)
			)
			(layer "F.Fab")
		)
		(fp_line
			(start -5.32511 -10.500106)
			(end 5.32511 -10.500106)
			(stroke
				(width 0.1)
				(type default)
			)
			(layer "F.Fab")
		)
		(fp_line
			(start 5.32511 -10.500106)
			(end 5.32511 21.299932)
			(stroke
				(width 0.1)
				(type default)
			)
			(layer "F.Fab")
		)
		(pad "" np_thru_hole circle
			(at 0 -6.620002 270)
			(size 3.9624 3.9624)
			(drill 3.9624)
			(layers "*.Cu" "*.Mask")
			(clearance 0.381)
			(thermal_gap 0.381)
		)
		(pad "" np_thru_hole circle
			(at 0 0 270)
			(size 0 0)
			(drill 3.9624)
			(layers "*.Cu" "*.Mask")
			(clearance 0)
		)
		(pad "" np_thru_hole circle
			(at 0 5.62991 270)
			(size 3.9624 3.9624)
			(drill 3.9624)
			(layers "*.Cu" "*.Mask")
			(clearance 0.381)
			(thermal_gap 0.381)
		)
		(zone
			(layers "F.Cu" "B.Cu" "In1.Cu" "In2.Cu" "In3.Cu" "In4.Cu" "In5.Cu" "In6.Cu"
				"In7.Cu" "In8.Cu"
			)
			(hatch none 0.5)
			(connect_pads
				(clearance 0)
			)
			(min_thickness 0.25)
			(keepout
				(tracks not_allowed)
				(vias allowed)
				(pads allowed)
				(copperpour not_allowed)
				(footprints allowed)
			)
			(placement
				(enabled no)
				(sheetname "")
			)
			(fill
				(thermal_gap 0.5)
				(thermal_bridge_width 0.5)
				(island_removal_mode 0)
			)
			(polygon
				(pts
					(arc
						(start 17.88922 -122.48007)
						(mid 12.91082 -122.48007)
						(end 17.88922 -122.48007)
					)
				)
			)
		)
		(zone
			(layers "F.Cu" "B.Cu" "In1.Cu" "In2.Cu" "In3.Cu" "In4.Cu" "In5.Cu" "In6.Cu"
				"In7.Cu" "In8.Cu"
			)
			(hatch none 0.5)
			(connect_pads
				(clearance 0)
			)
			(min_thickness 0.25)
			(keepout
				(tracks not_allowed)
				(vias allowed)
				(pads allowed)
				(copperpour not_allowed)
				(footprints allowed)
			)
			(placement
				(enabled no)
				(sheetname "")
			)
			(fill
				(thermal_gap 0.5)
				(thermal_bridge_width 0.5)
				(island_removal_mode 0)
			)
			(polygon
				(pts
					(arc
						(start 30.139132 -122.48007)
						(mid 25.160732 -122.48007)
						(end 30.139132 -122.48007)
					)
				)
			)
		)
		(zone
			(layers "F.Cu" "B.Cu" "In1.Cu" "In2.Cu" "In3.Cu" "In4.Cu" "In5.Cu" "In6.Cu"
				"In7.Cu" "In8.Cu"
			)
			(hatch none 0.5)
			(connect_pads
				(clearance 0)
			)
			(min_thickness 0.25)
			(keepout
				(tracks not_allowed)
				(vias allowed)
				(pads allowed)
				(copperpour not_allowed)
				(footprints allowed)
			)
			(placement
				(enabled no)
				(sheetname "")
			)
			(fill
				(thermal_gap 0.5)
				(thermal_bridge_width 0.5)
				(island_removal_mode 0)
			)
			(polygon
				(pts
					(arc
						(start 25.04313 -122.48007)
						(mid 17.01673 -122.48007)
						(end 25.04313 -122.48007)
					)
				)
			)
		)
	)
	(footprint ""
		(layer "F.Cu")
		(at 164.714174 -130.175)
		(property "Reference" "PC120"
			(at 0 0 0)
			(layer "F.SilkS")
			(hide yes)
			(effects
				(font
					(size 1.27 1.27)
				)
			)
		)
		(property "Value" ""
			(at 0 0 0)
			(layer "F.Fab")
			(effects
				(font
					(size 1.27 1.27)
				)
			)
		)
		(duplicate_pad_numbers_are_jumpers no)
		(fp_line
			(start -2.2098 -0.9398)
			(end 2.2098 -0.9398)
			(stroke
				(width 0.1524)
				(type default)
			)
			(layer "F.SilkS")
		)
		(fp_line
			(start -2.2098 0.9398)
			(end -2.2098 -0.9398)
			(stroke
				(width 0.1524)
				(type default)
			)
			(layer "F.SilkS")
		)
		(fp_line
			(start 2.2098 -0.9398)
			(end 2.2098 0.9398)
			(stroke
				(width 0.1524)
				(type default)
			)
			(layer "F.SilkS")
		)
		(fp_line
			(start 2.2098 0.9398)
			(end -2.2098 0.9398)
			(stroke
				(width 0.1524)
				(type default)
			)
			(layer "F.SilkS")
		)
		(fp_line
			(start -1.700022 -0.899922)
			(end 1.700022 -0.899922)
			(stroke
				(width 0.1)
				(type default)
			)
			(layer "F.Fab")
		)
		(fp_line
			(start -1.700022 0.899922)
			(end -1.700022 -0.899922)
			(stroke
				(width 0.1)
				(type default)
			)
			(layer "F.Fab")
		)
		(fp_line
			(start 1.700022 -0.899922)
			(end 1.700022 0.899922)
			(stroke
				(width 0.1)
				(type default)
			)
			(layer "F.Fab")
		)
		(fp_line
			(start 1.700022 0.899922)
			(end -1.700022 0.899922)
			(stroke
				(width 0.1)
				(type default)
			)
			(layer "F.Fab")
		)
		(pad "1" smd rect
			(at -1.4732 0 180)
			(size 1.1684 1.5748)
			(layers "F.Cu" "F.Mask" "F.Paste")
			(net "P52V_HS_FILTER")
		)
		(pad "2" smd rect
			(at 1.4732 0 180)
			(size 1.1684 1.5748)
			(layers "F.Cu" "F.Mask" "F.Paste")
			(net "GND")
		)
	)
	(footprint ""
		(layer "F.Cu")
		(at 54.238906 -136.906 90)
		(property "Reference" "PC72"
			(at 6.06933 1.006094 0)
			(unlocked yes)
			(layer "F.SilkS")
			(effects
				(font
					(size 0.7874 0.5842)
					(thickness 0.1524)
				)
				(justify left)
			)
		)
		(property "Value" ""
			(at 0 0 90)
			(layer "F.Fab")
			(effects
				(font
					(size 1.27 1.27)
				)
			)
		)
		(duplicate_pad_numbers_are_jumpers no)
		(fp_line
			(start 5.2578 2.499868)
			(end -5.2578 2.499868)
			(stroke
				(width 0.1524)
				(type default)
			)
			(layer "F.SilkS")
		)
		(fp_circle
			(center 0 2.500122)
			(end 0 7.758176)
			(stroke
				(width 0.1524)
				(type default)
			)
			(fill no)
			(layer "F.SilkS")
		)
		(fp_poly
			(pts
				(arc
					(start 5.2578 2.499868)
					(mid 0 7.757922)
					(end -5.2578 2.499868)
				)
			)
			(stroke
				(width 0)
				(type default)
			)
			(fill yes)
			(layer "F.SilkS")
		)
		(fp_circle
			(center 0 2.500122)
			(end 0 7.758176)
			(stroke
				(width 0.1)
				(type default)
			)
			(fill no)
			(layer "F.Fab")
		)
		(pad "1" thru_hole rect
			(at 0 0)
			(size 1.5748 1.5748)
			(drill 1.0668)
			(layers "*.Cu" "*.Mask")
			(remove_unused_layers no)
			(net "P52V_HS_FILTER")
			(clearance 0)
			(padstack
				(mode front_inner_back)
				(layer "Inner"
					(shape circle)
					(size 1.5748 1.5748)
					(clearance 0)
				)
				(layer "B.Cu"
					(shape rect)
					(size 1.5748 1.5748)
					(clearance 0)
				)
			)
		)
		(pad "2" thru_hole circle
			(at 0 4.99999)
			(size 1.5748 1.5748)
			(drill 1.0668)
			(layers "*.Cu" "*.Mask")
			(remove_unused_layers no)
			(net "GND")
			(clearance 0)
		)
	)
	(footprint ""
		(layer "F.Cu")
		(at 104.469946 -121.209816)
		(property "Reference" "PU3"
			(at -26.563066 -5.12953 0)
			(unlocked yes)
			(layer "F.SilkS")
			(effects
				(font
					(size 0.7874 0.5842)
					(thickness 0.1524)
				)
				(justify left)
			)
		)
		(property "Value" ""
			(at 0 0 0)
			(layer "F.Fab")
			(effects
				(font
					(size 1.27 1.27)
				)
			)
		)
		(duplicate_pad_numbers_are_jumpers no)
		(fp_line
			(start -26.519886 -4.299966)
			(end -26.519886 55.099966)
			(stroke
				(width 0.1524)
				(type default)
			)
			(layer "F.SilkS")
		)
		(fp_line
			(start -26.519886 55.099966)
			(end 11.279886 55.099966)
			(stroke
				(width 0.1524)
				(type default)
			)
			(layer "F.SilkS")
		)
		(fp_line
			(start -26.020014 -3.800094)
			(end -26.020014 54.59984)
			(stroke
				(width 0.1524)
				(type default)
			)
			(layer "F.SilkS")
		)
		(fp_line
			(start -26.020014 54.59984)
			(end 10.780014 54.59984)
			(stroke
				(width 0.1524)
				(type default)
			)
			(layer "F.SilkS")
		)
		(fp_line
			(start 10.780014 -3.800094)
			(end -26.020014 -3.800094)
			(stroke
				(width 0.1524)
				(type default)
			)
			(layer "F.SilkS")
		)
		(fp_line
			(start 10.780014 54.59984)
			(end 10.780014 -3.800094)
			(stroke
				(width 0.1524)
				(type default)
			)
			(layer "F.SilkS")
		)
		(fp_line
			(start 11.279886 -4.299966)
			(end -26.519886 -4.299966)
			(stroke
				(width 0.1524)
				(type default)
			)
			(layer "F.SilkS")
		)
		(fp_line
			(start 11.279886 55.099966)
			(end 11.279886 -4.299966)
			(stroke
				(width 0.1524)
				(type default)
			)
			(layer "F.SilkS")
		)
		(fp_poly
			(pts
				(xy 1.27 -7.44728) (xy -1.27 -7.44728) (xy 0 -4.90728)
			)
			(stroke
				(width 0)
				(type default)
			)
			(fill yes)
			(layer "F.SilkS")
		)
		(fp_line
			(start -26.020014 -3.800094)
			(end -26.020014 54.59984)
			(stroke
				(width 0.1)
				(type default)
			)
			(layer "F.Fab")
		)
		(fp_line
			(start -26.020014 54.59984)
			(end 10.780014 54.59984)
			(stroke
				(width 0.1)
				(type default)
			)
			(layer "F.Fab")
		)
		(fp_line
			(start 10.780014 -3.800094)
			(end -26.020014 -3.800094)
			(stroke
				(width 0.1)
				(type default)
			)
			(layer "F.Fab")
		)
		(fp_line
			(start 10.780014 54.59984)
			(end 10.780014 -3.800094)
			(stroke
				(width 0.1)
				(type default)
			)
			(layer "F.Fab")
		)
		(fp_poly
			(pts
				(xy 1.27 -7.44728) (xy -1.27 -7.44728) (xy 0 -4.90728)
			)
			(stroke
				(width 0)
				(type default)
			)
			(fill yes)
			(layer "F.Fab")
		)
		(pad "1" thru_hole rect
			(at 0 0 270)
			(size 2.3622 2.3622)
			(drill 1.6002)
			(layers "*.Cu" "*.Mask")
			(remove_unused_layers no)
			(net "P52V_HS_FILTER")
			(clearance -0.127)
			(padstack
				(mode front_inner_back)
				(layer "Inner"
					(shape circle)
					(size 2.3622 2.3622)
					(clearance -0.127)
				)
				(layer "B.Cu"
					(shape rect)
					(size 2.3622 2.3622)
					(clearance -0.127)
				)
			)
		)
		(pad "2" thru_hole circle
			(at -7.62 0 270)
			(size 2.3622 2.3622)
			(drill 1.6002)
			(layers "*.Cu" "*.Mask")
			(remove_unused_layers no)
			(net "BRICK_P12V1_ON_OFF_R")
			(clearance -0.127)
		)
		(pad "3" thru_hole circle
			(at -15.24 0 270)
			(size 2.3622 2.3622)
			(drill 1.6002)
			(layers "*.Cu" "*.Mask")
			(remove_unused_layers no)
			(net "GND")
			(clearance -0.127)
		)
		(pad "4" thru_hole circle
			(at -19.05 50.8 270)
			(size 3.1242 3.1242)
			(drill 2.1082)
			(layers "*.Cu" "*.Mask")
			(remove_unused_layers no)
			(net "GND")
			(clearance -0.254)
		)
		(pad "5" thru_hole circle
			(at -15.24 50.8 270)
			(size 3.1242 3.1242)
			(drill 2.1082)
			(layers "*.Cu" "*.Mask")
			(remove_unused_layers no)
			(net "GND")
			(clearance -0.254)
		)
		(pad "6" thru_hole circle
			(at 0 50.8 270)
			(size 3.1242 3.1242)
			(drill 2.1082)
			(layers "*.Cu" "*.Mask")
			(remove_unused_layers no)
			(net "P12V_BRICK")
			(clearance -0.254)
		)
		(pad "7" thru_hole circle
			(at 3.81 50.8 270)
			(size 3.1242 3.1242)
			(drill 2.1082)
			(layers "*.Cu" "*.Mask")
			(remove_unused_layers no)
			(net "P12V_BRICK")
			(clearance -0.254)
		)
		(pad "8" thru_hole circle
			(at -13.619988 53.34 270)
			(size 1.3208 1.3208)
			(drill 0.9144)
			(layers "*.Cu" "*.Mask")
			(remove_unused_layers no)
			(net "P12V_BRICK_PWRGD")
			(clearance 0.0508)
			(thermal_gap 0.0508)
		)
		(pad "9" thru_hole circle
			(at -11.619992 53.34 270)
			(size 1.3208 1.3208)
			(drill 0.9144)
			(layers "*.Cu" "*.Mask")
			(remove_unused_layers no)
			(net "P12V_MB1_SENSE-")
			(clearance 0.0508)
			(thermal_gap 0.0508)
		)
		(pad "10" thru_hole circle
			(at -9.619996 53.34 270)
			(size 1.3208 1.3208)
			(drill 0.9144)
			(layers "*.Cu" "*.Mask")
			(remove_unused_layers no)
			(net "SMB_BRICK1_SDA")
			(clearance 0.0508)
			(thermal_gap 0.0508)
		)
		(pad "11" thru_hole circle
			(at -7.62 53.34 270)
			(size 1.3208 1.3208)
			(drill 0.9144)
			(layers "*.Cu" "*.Mask")
			(remove_unused_layers no)
			(net "SMB_BRICK1_ALERT")
			(clearance 0.0508)
			(thermal_gap 0.0508)
		)
		(pad "12" thru_hole circle
			(at -5.620004 53.34 270)
			(size 1.3208 1.3208)
			(drill 0.9144)
			(layers "*.Cu" "*.Mask")
			(remove_unused_layers no)
			(net "SMB_BRICK1_SCL")
			(clearance 0.0508)
			(thermal_gap 0.0508)
		)
		(pad "13" thru_hole circle
			(at -3.620008 53.34 270)
			(size 1.3208 1.3208)
			(drill 0.9144)
			(layers "*.Cu" "*.Mask")
			(remove_unused_layers no)
			(net "BRICK1_PMBADD")
			(clearance 0.0508)
			(thermal_gap 0.0508)
		)
		(pad "14" thru_hole circle
			(at -1.620012 53.34 270)
			(size 1.3208 1.3208)
			(drill 0.9144)
			(layers "*.Cu" "*.Mask")
			(remove_unused_layers no)
			(net "P12V_MB1_SENSE+")
			(clearance 0.0508)
			(thermal_gap 0.0508)
		)
	)
)
